# T6G (Grand Teton) — schematic netlist excerpt (pin names and nets, part order shuffled) for the footprints in the layout excerpt that follows; sources: Cadence DE-HDL packaged netlist, KiCad conversion of 04192023_DAF0TMB3IC0_F0TG_MB_C_brd_V02_OCP.brd

J102  SCONN288_DDR506112002KQ  IO  pkg DDR288S_1-1VXC  page 104
  VIN_BULK0  = P12V_MEM_CPU1
  RFU0  = NC
  VIN_MGMT  = P3V3_AUX
  HSCL  = I3C_SPD_DDRG_CPU1_SCL
  HSDA  = I3C_SPD_DDRG_CPU1_SDA
  VSS0  = GND
  DQ0_A  = M_G_CPU1_SA_DQ<0>
  VSS1  = GND
  DQ1_A  = M_G_CPU1_SA_DQ<1>
  VSS2  = GND
  DQS0_A_T  = M_G_CPU1_SA_DQS_DP<0>
  DQS0_A_C  = M_G_CPU1_SA_DQS_DN<0>
  VSS3  = GND
  DQ4_A  = M_G_CPU1_SA_DQ<4>
  VSS4  = GND
  DQ5_A  = M_G_CPU1_SA_DQ<5>
  VSS5  = GND
  DQ8_A  = M_G_CPU1_SA_DQ<8>
  VSS6  = GND
  DQ9_A  = M_G_CPU1_SA_DQ<9>
  VSS7  = GND
  DQS1_A_T  = M_G_CPU1_SA_DQS_DP<1>
  DQS1_A_C  = M_G_CPU1_SA_DQS_DN<1>
  VSS8  = GND
  DQ12_A  = M_G_CPU1_SA_DQ<12>
  VSS9  = GND
  DQ13_A  = M_G_CPU1_SA_DQ<13>
  VSS10  = GND
  DQ16_A  = M_G_CPU1_SA_DQ<16>
  VSS11  = GND
  DQ17_A  = M_G_CPU1_SA_DQ<17>
  VSS12  = GND
  DQS2_A_T  = M_G_CPU1_SA_DQS_DP<2>
  DQS2_A_C  = M_G_CPU1_SA_DQS_DN<2>
  VSS13  = GND
  DQ20_A  = M_G_CPU1_SA_DQ<20>
  VSS14  = GND
  DQ21_A  = M_G_CPU1_SA_DQ<21>
  VSS15  = GND
  DQ24_A  = M_G_CPU1_SA_DQ<24>
  VSS16  = GND
  DQ25_A  = M_G_CPU1_SA_DQ<25>
  VSS17  = GND
  DQS3_A_T  = M_G_CPU1_SA_DQS_DP<3>
  DQS3_A_C  = M_G_CPU1_SA_DQS_DN<3>
  VSS18  = GND
  DQ28_A  = M_G_CPU1_SA_DQ<28>
  VSS19  = GND
  DQ29_A  = M_G_CPU1_SA_DQ<29>
  VSS20  = GND
  CB0_A  = M_G_CPU1_SA_CB<0>
  VSS21  = GND
  CB1_A  = M_G_CPU1_SA_CB<1>
  VSS22  = GND
  DQS4_A_T  = M_G_CPU1_SA_DQS_DP<4>
  DQS4_A_C  = M_G_CPU1_SA_DQS_DN<4>
  VSS23  = GND
  CB4_A  = M_G_CPU1_SA_CB<4>
  VSS24  = GND
  CB5_A  = M_G_CPU1_SA_CB<5>
  VSS25  = GND
  ALERT_N  = M_G_CPU1_ALERT_N
  VSS26  = GND
  CS0_A_N  = M_G_CPU1_SA_CS_N<0>
  VSS27  = GND
  CA0_A  = M_G_CPU1_SA_CA<0>
  VSS28  = GND
  CA2_A  = M_G_CPU1_SA_CA<2>
  VSS29  = GND
  CA4_A  = M_G_CPU1_SA_CA<4>
  VSS30  = GND
  CA6_A  = M_G_CPU1_SA_CA<6>
  VSS31  = GND
  PAR_A  = M_G_CPU1_SA_PAR
  VSS32  = GND
  CA0_B  = M_G_CPU1_SB_CA<0>
  VSS33  = GND
  CA2_B  = M_G_CPU1_SB_CA<2>
  VSS34  = GND
  CA4_B  = M_G_CPU1_SB_CA<4>
  VSS35  = GND
  CA6_B  = M_G_CPU1_SB_CA<6>
  VSS36  = GND
  CS0_B_N  = M_G_CPU1_SB_CS_N<0>
  VSS37  = GND
  \lbd||rsp_a_n\  = M_G_CPU1_SA_RSP<0>
  \lbs||rsp_b_n\  = M_G_CPU1_SB_RSP<0>
  VSS38  = GND
  CB4_B  = M_G_CPU1_SB_CB<4>
  VSS39  = GND
  CB5_B  = M_G_CPU1_SB_CB<5>
  VSS40  = GND
  \dqs9_b_t||tdqs9_b_t||dbi4_b_n\  = M_G_CPU1_SB_DQS_DP<9>
  \dqs9_b_c||tdqs9_b_c\  = M_G_CPU1_SB_DQS_DN<9>
  VSS41  = GND
  CB0_B  = M_G_CPU1_SB_CB<0>
  VSS42  = GND
  CB1_B  = M_G_CPU1_SB_CB<1>
  VSS43  = GND
  DQ0_B  = M_G_CPU1_SB_DQ<0>
  VSS44  = GND
  DQ1_B  = M_G_CPU1_SB_DQ<1>
  VSS45  = GND
  DQS0_B_T  = M_G_CPU1_SB_DQS_DP<0>
  DQS0_B_C  = M_G_CPU1_SB_DQS_DN<0>
  VSS46  = GND
  DQ4_B  = M_G_CPU1_SB_DQ<4>
  VSS47  = GND
  DQ5_B  = M_G_CPU1_SB_DQ<5>
  VSS48  = GND
  DQ8_B  = M_G_CPU1_SB_DQ<8>
  VSS49  = GND
  DQ9_B  = M_G_CPU1_SB_DQ<9>
  VSS50  = GND
  DQS1_B_T  = M_G_CPU1_SB_DQS_DP<1>
  DQS1_B_C  = M_G_CPU1_SB_DQS_DN<1>
  VSS51  = GND
  DQ12_B  = M_G_CPU1_SB_DQ<12>
  VSS52  = GND
  DQ13_B  = M_G_CPU1_SB_DQ<13>
  VSS53  = GND
  DQ16_B  = M_G_CPU1_SB_DQ<16>
  VSS54  = GND
  DQ17_B  = M_G_CPU1_SB_DQ<17>
  VSS55  = GND
  DQS2_B_T  = M_G_CPU1_SB_DQS_DP<2>
  DQS2_B_C  = M_G_CPU1_SB_DQS_DN<2>
  VSS56  = GND
  DQ20_B  = M_G_CPU1_SB_DQ<20>
  VSS57  = GND
  DQ21_B  = M_G_CPU1_SB_DQ<21>
  VSS58  = GND
  DQ24_B  = M_G_CPU1_SB_DQ<24>
  VSS59  = GND
  DQ25_B  = M_G_CPU1_SB_DQ<25>
  VSS60  = GND
  DQS3_B_T  = M_G_CPU1_SB_DQS_DP<3>
  DQS3_B_C  = M_G_CPU1_SB_DQS_DN<3>
  VSS61  = GND
  DQ28_B  = M_G_CPU1_SB_DQ<28>
  VSS62  = GND
  DQ29_B  = M_G_CPU1_SB_DQ<29>
  VSS63  = GND
  RFU1  = NC
  VIN_BULK1  = P12V_MEM_CPU1
  VIN_BULK2  = P12V_MEM_CPU1
  \pwr_good||fail_n\  = PWRGD_CHG_CPU1_DIMM0
  HAS  = PD_CHG_CPU1_DIMM0_SAA
  RFU2  = NC
  RFU3  = NC
  VSS64  = GND
  DQ2_A  = M_G_CPU1_SA_DQ<2>
  VSS65  = GND
  DQ3_A  = M_G_CPU1_SA_DQ<3>
  VSS66  = GND
  \dqs5_a_c||tdqs5_a_c||dqs5_a_t||tdqs5_a_t\  = M_G_CPU1_SA_DQS_DN<5>
  \dqs5_a_t||tdqs5_a_t\  = M_G_CPU1_SA_DQS_DP<5>
  VSS67  = GND
  DQ6_A  = M_G_CPU1_SA_DQ<6>
  VSS68  = GND
  DQ7_A  = M_G_CPU1_SA_DQ<7>
  VSS69  = GND
  DQ10_A  = M_G_CPU1_SA_DQ<10>
  VSS70  = GND
  DQ11_A  = M_G_CPU1_SA_DQ<11>
  VSS71  = GND
  \dqs6_a_c||tdqs6_a_c||dqs6_a_t||tdqs6_a_t\  = M_G_CPU1_SA_DQS_DN<6>
  \dqs6_a_t||tdqs6_a_t\  = M_G_CPU1_SA_DQS_DP<6>
  VSS72  = GND
  DQ14_A  = M_G_CPU1_SA_DQ<14>
  VSS73  = GND
  DQ15_A  = M_G_CPU1_SA_DQ<15>
  VSS74  = GND
  DQ18_A  = M_G_CPU1_SA_DQ<18>
  VSS75  = GND
  DQ19_A  = M_G_CPU1_SA_DQ<19>
  VSS76  = GND
  \dqs7_a_c||tdqs7_a_c\  = M_G_CPU1_SA_DQS_DN<7>
  \dqs7_a_t||tdqs7_a_t\  = M_G_CPU1_SA_DQS_DP<7>
  VSS77  = GND
  DQ22_A  = M_G_CPU1_SA_DQ<22>
  VSS78  = GND
  DQ23_A  = M_G_CPU1_SA_DQ<23>
  VSS79  = GND
  DQ26_A  = M_G_CPU1_SA_DQ<26>
  VSS80  = GND
  DQ27_A  = M_G_CPU1_SA_DQ<27>
  VSS81  = GND
  \dqs8_a_c||tdqs8_a_c\  = M_G_CPU1_SA_DQS_DN<8>
  \dqs8_a_t||tdqs8_a_t\  = M_G_CPU1_SA_DQS_DP<8>
  VSS82  = GND
  DQ30_A  = M_G_CPU1_SA_DQ<30>
  VSS83  = GND
  DQ31_A  = M_G_CPU1_SA_DQ<31>
  VSS84  = GND
  CB2_A  = M_G_CPU1_SA_CB<2>
  VSS85  = GND
  CB3_A  = M_G_CPU1_SA_CB<3>
  VSS86  = GND
  \dqs9_a_c||tdqs9_a_c\  = M_G_CPU1_SA_DQS_DN<9>
  \dqs9_a_t||tdqs9_a_t\  = M_G_CPU1_SA_DQS_DP<9>
  VSS87  = GND
  CB6_A  = M_G_CPU1_SA_CB<6>
  VSS88  = GND
  CB7_A  = M_G_CPU1_SA_CB<7>
  VSS89  = GND
  RESET_N  = M_G_CPU1_RESET_N
  VSS90  = GND
  CS1_A_N  = M_G_CPU1_SA_CS_N<1>
  VSS91  = GND
  CA1_A  = M_G_CPU1_SA_CA<1>
  VSS92  = GND
  CA3_A  = M_G_CPU1_SA_CA<3>
  VSS93  = GND
  CA5_A  = M_G_CPU1_SA_CA<5>
  VSS94  = GND
  CK_T  = M_G_CPU1_CLK_DP<0>
  CK_C  = M_G_CPU1_CLK_DN<0>
  VSS95  = GND
  RFU4  = NC
  CA1_B  = M_G_CPU1_SB_CA<1>
  VSS96  = GND
  CA3_B  = M_G_CPU1_SB_CA<3>
  VSS97  = GND
  CA5_B  = M_G_CPU1_SB_CA<5>
  VSS98  = GND
  PAR_B  = M_G_CPU1_SB_PAR
  VSS99  = GND
  CS1_B_N  = M_G_CPU1_SB_CS_N<1>
  VSS100  = GND
  RFU5  = NC
  RFU6  = NC
  VSS101  = GND
  CB6_B  = M_G_CPU1_SB_CB<6>
  VSS102  = GND
  CB7_B  = M_G_CPU1_SB_CB<7>
  VSS103  = GND
  DQS4_B_C  = M_G_CPU1_SB_DQS_DN<4>
  DQS4_B_T  = M_G_CPU1_SB_DQS_DP<4>
  VSS104  = GND
  CB2_B  = M_G_CPU1_SB_CB<2>
  VSS105  = GND
  CB3_B  = M_G_CPU1_SB_CB<3>
  VSS106  = GND
  DQ2_B  = M_G_CPU1_SB_DQ<2>
  VSS107  = GND
  DQ3_B  = M_G_CPU1_SB_DQ<3>
  VSS108  = GND
  \dqs5_b_c||tdqs5_b_c\  = M_G_CPU1_SB_DQS_DN<5>
  \dqs5_b_t||tdqs5_b_t\  = M_G_CPU1_SB_DQS_DP<5>
  VSS109  = GND
  DQ6_B  = M_G_CPU1_SB_DQ<6>
  VSS110  = GND
  DQ7_B  = M_G_CPU1_SB_DQ<7>
  VSS111  = GND
  DQ10_B  = M_G_CPU1_SB_DQ<10>
  VSS112  = GND
  DQ11_B  = M_G_CPU1_SB_DQ<11>
  VSS113  = GND
  \dqs6_b_c||tdqs6_b_c\  = M_G_CPU1_SB_DQS_DN<6>
  \dqs6_b_t||tdqs6_b_t\  = M_G_CPU1_SB_DQS_DP<6>
  VSS114  = GND
  DQ14_B  = M_G_CPU1_SB_DQ<14>
  VSS115  = GND
  DQ15_B  = M_G_CPU1_SB_DQ<15>
  VSS116  = GND
  DQ18_B  = M_G_CPU1_SB_DQ<18>
  VSS117  = GND
  DQ19_B  = M_G_CPU1_SB_DQ<19>
  VSS118  = GND
  \dqs7_b_c||tdqs7_b_c\  = M_G_CPU1_SB_DQS_DN<7>
  \dqs7_b_t||tdqs7_b_t\  = M_G_CPU1_SB_DQS_DP<7>
  VSS119  = GND
  DQ22_B  = M_G_CPU1_SB_DQ<22>
  VSS120  = GND
  DQ23_B  = M_G_CPU1_SB_DQ<23>
  VSS121  = GND
  DQ26_B  = M_G_CPU1_SB_DQ<26>
  VSS122  = GND
  DQ27_B  = M_G_CPU1_SB_DQ<27>
  VSS123  = GND
  \dqs8_b_c||tdqs8_b_c\  = M_G_CPU1_SB_DQS_DN<8>
  \dqs8_b_t||tdqs8_b_t\  = M_G_CPU1_SB_DQS_DP<8>
  VSS124  = GND
  DQ30_B  = M_G_CPU1_SB_DQ<30>
  VSS125  = GND
  DQ31_B  = M_G_CPU1_SB_DQ<31>
  VSS126  = GND
  G1  = GND
  G2  = GND
  G3  = GND

(kicad_pcb
	(version 20260206)
	(generator "pcbnew")
	(generator_version "10.0")
	(general
		(thickness 1.6)
		(legacy_teardrops no)
	)
	(paper "A4")
	(title_block
		(title "04192023_DAF0TMB3IC0_F0TG_MB_C_brd_V02_OCP.brd")
		(comment 1 "Grand Teton / footprint 4934 of 8354 (J102), pads 1-46 of 291")
	)
	(layers
		(0 "F.Cu" signal "TOP")
		(4 "In1.Cu" signal "GND")
		(6 "In2.Cu" signal "IN1")
		(8 "In3.Cu" signal "GND1")
		(10 "In4.Cu" signal "IN2")
		(12 "In5.Cu" signal "GND2")
		(14 "In6.Cu" signal "IN3")
		(16 "In7.Cu" signal "GND3")
		(18 "In8.Cu" signal "VCC")
		(20 "In9.Cu" signal "VCC1")
		(22 "In10.Cu" signal "GND4")
		(24 "In11.Cu" signal "IN4")
		(26 "In12.Cu" signal "GND5")
		(28 "In13.Cu" signal "IN5")
		(30 "In14.Cu" signal "GND6")
		(32 "In15.Cu" signal "IN6")
		(34 "In16.Cu" signal "GND7")
		(2 "B.Cu" signal "BOTTOM")
		(9 "F.Adhes" user "F.Adhesive")
		(11 "B.Adhes" user "B.Adhesive")
		(13 "F.Paste" user "Package Geometry/Pastemask Top")
		(15 "B.Paste" user "Package Geometry/Pastemask Bottom")
		(5 "F.SilkS" user "Ref Des/Silkscreen Top")
		(7 "B.SilkS" user "Ref Des/Silkscreen Bottom")
		(1 "F.Mask" user "Board Geometry/Soldermask Top")
		(3 "B.Mask" user "Board Geometry/Soldermask Bottom")
		(17 "Dwgs.User" user "User.Drawings")
		(19 "Cmts.User" user "User.Comments")
		(21 "Eco1.User" user "User.Eco1")
		(23 "Eco2.User" user "User.Eco2")
		(25 "Edge.Cuts" user "Board Geometry/Outline")
		(27 "Margin" user)
		(31 "F.CrtYd" user "Package Geometry/Place Bound Top")
		(29 "B.CrtYd" user "Package Geometry/Place Bound Bottom")
		(35 "F.Fab" user "Ref Des/Assembly Top")
		(33 "B.Fab" user "Ref Des/Assembly Bottom")
	)
	(footprint ""
		(layer "F.Cu")
		(at 166.47795 -255.560322 180)
		(property "Reference" "J102"
			(at -2.7178 -81.857088 0)
			(unlocked yes)
			(layer "F.SilkS")
			(effects
				(font
					(size 0.7874 0.5842)
					(thickness 0.1524)
				)
			)
		)
		(property "Value" ""
			(at 0 0 180)
			(layer "F.Fab")
			(effects
				(font
					(size 1.27 1.27)
				)
			)
		)
		(duplicate_pad_numbers_are_jumpers no)
		(pad "1" smd rect
			(at -2.050034 -63.324994 90)
			(size 0.519938 1.4986)
			(layers "F.Cu" "F.Mask" "F.Paste")
			(net "P12V_MEM_CPU1")
		)
		(pad "2" smd rect
			(at -2.050034 -62.47511 90)
			(size 0.519938 1.4986)
			(layers "F.Cu" "F.Mask" "F.Paste")
			(net "Net_2340")
		)
		(pad "3" smd rect
			(at -2.050034 -61.624972 90)
			(size 0.519938 1.4986)
			(layers "F.Cu" "F.Mask" "F.Paste")
			(net "P3V3_AUX")
		)
		(pad "4" smd rect
			(at -2.050034 -60.775088 90)
			(size 0.519938 1.4986)
			(layers "F.Cu" "F.Mask" "F.Paste")
			(net "I3C_SPD_DDRG_CPU1_SCL")
		)
		(pad "5" smd rect
			(at -2.050034 -59.92495 90)
			(size 0.519938 1.4986)
			(layers "F.Cu" "F.Mask" "F.Paste")
			(net "I3C_SPD_DDRG_CPU1_SDA")
		)
		(pad "6" smd rect
			(at -2.050034 -59.075066 90)
			(size 0.519938 1.4986)
			(layers "F.Cu" "F.Mask" "F.Paste")
			(net "GND")
		)
		(pad "7" smd rect
			(at -2.050034 -58.224928 90)
			(size 0.519938 1.4986)
			(layers "F.Cu" "F.Mask" "F.Paste")
			(net "M_G_CPU1_SA_DQ<0>")
		)
		(pad "8" smd rect
			(at -2.050034 -57.375044 90)
			(size 0.519938 1.4986)
			(layers "F.Cu" "F.Mask" "F.Paste")
			(net "GND")
		)
		(pad "9" smd rect
			(at -2.050034 -56.524906 90)
			(size 0.519938 1.4986)
			(layers "F.Cu" "F.Mask" "F.Paste")
			(net "M_G_CPU1_SA_DQ<1>")
		)
		(pad "10" smd rect
			(at -2.050034 -55.675022 90)
			(size 0.519938 1.4986)
			(layers "F.Cu" "F.Mask" "F.Paste")
			(net "GND")
		)
		(pad "11" smd rect
			(at -2.050034 -54.824884 90)
			(size 0.519938 1.4986)
			(layers "F.Cu" "F.Mask" "F.Paste")
			(net "M_G_CPU1_SA_DQS_DP<0>")
		)
		(pad "12" smd rect
			(at -2.050034 -53.975 90)
			(size 0.519938 1.4986)
			(layers "F.Cu" "F.Mask" "F.Paste")
			(net "M_G_CPU1_SA_DQS_DN<0>")
		)
		(pad "13" smd rect
			(at -2.050034 -53.125116 90)
			(size 0.519938 1.4986)
			(layers "F.Cu" "F.Mask" "F.Paste")
			(net "GND")
		)
		(pad "14" smd rect
			(at -2.050034 -52.274978 90)
			(size 0.519938 1.4986)
			(layers "F.Cu" "F.Mask" "F.Paste")
			(net "M_G_CPU1_SA_DQ<4>")
		)
		(pad "15" smd rect
			(at -2.050034 -51.425094 90)
			(size 0.519938 1.4986)
			(layers "F.Cu" "F.Mask" "F.Paste")
			(net "GND")
		)
		(pad "16" smd rect
			(at -2.050034 -50.574956 90)
			(size 0.519938 1.4986)
			(layers "F.Cu" "F.Mask" "F.Paste")
			(net "M_G_CPU1_SA_DQ<5>")
		)
		(pad "17" smd rect
			(at -2.050034 -49.725072 90)
			(size 0.519938 1.4986)
			(layers "F.Cu" "F.Mask" "F.Paste")
			(net "GND")
		)
		(pad "18" smd rect
			(at -2.050034 -48.874934 90)
			(size 0.519938 1.4986)
			(layers "F.Cu" "F.Mask" "F.Paste")
			(net "M_G_CPU1_SA_DQ<8>")
		)
		(pad "19" smd rect
			(at -2.050034 -48.02505 90)
			(size 0.519938 1.4986)
			(layers "F.Cu" "F.Mask" "F.Paste")
			(net "GND")
		)
		(pad "20" smd rect
			(at -2.050034 -47.174912 90)
			(size 0.519938 1.4986)
			(layers "F.Cu" "F.Mask" "F.Paste")
			(net "M_G_CPU1_SA_DQ<9>")
		)
		(pad "21" smd rect
			(at -2.050034 -46.325028 90)
			(size 0.519938 1.4986)
			(layers "F.Cu" "F.Mask" "F.Paste")
			(net "GND")
		)
		(pad "22" smd rect
			(at -2.050034 -45.47489 90)
			(size 0.519938 1.4986)
			(layers "F.Cu" "F.Mask" "F.Paste")
			(net "M_G_CPU1_SA_DQS_DP<1>")
		)
		(pad "23" smd rect
			(at -2.050034 -44.625006 90)
			(size 0.519938 1.4986)
			(layers "F.Cu" "F.Mask" "F.Paste")
			(net "M_G_CPU1_SA_DQS_DN<1>")
		)
		(pad "24" smd rect
			(at -2.050034 -43.775122 90)
			(size 0.519938 1.4986)
			(layers "F.Cu" "F.Mask" "F.Paste")
			(net "GND")
		)
		(pad "25" smd rect
			(at -2.050034 -42.924984 90)
			(size 0.519938 1.4986)
			(layers "F.Cu" "F.Mask" "F.Paste")
			(net "M_G_CPU1_SA_DQ<12>")
		)
		(pad "26" smd rect
			(at -2.050034 -42.0751 90)
			(size 0.519938 1.4986)
			(layers "F.Cu" "F.Mask" "F.Paste")
			(net "GND")
		)
		(pad "27" smd rect
			(at -2.050034 -41.224962 90)
			(size 0.519938 1.4986)
			(layers "F.Cu" "F.Mask" "F.Paste")
			(net "M_G_CPU1_SA_DQ<13>")
		)
		(pad "28" smd rect
			(at -2.050034 -40.375078 90)
			(size 0.519938 1.4986)
			(layers "F.Cu" "F.Mask" "F.Paste")
			(net "GND")
		)
		(pad "29" smd rect
			(at -2.050034 -39.52494 90)
			(size 0.519938 1.4986)
			(layers "F.Cu" "F.Mask" "F.Paste")
			(net "M_G_CPU1_SA_DQ<16>")
		)
		(pad "30" smd rect
			(at -2.050034 -38.675056 90)
			(size 0.519938 1.4986)
			(layers "F.Cu" "F.Mask" "F.Paste")
			(net "GND")
		)
		(pad "31" smd rect
			(at -2.050034 -37.824918 90)
			(size 0.519938 1.4986)
			(layers "F.Cu" "F.Mask" "F.Paste")
			(net "M_G_CPU1_SA_DQ<17>")
		)
		(pad "32" smd rect
			(at -2.050034 -36.975034 90)
			(size 0.519938 1.4986)
			(layers "F.Cu" "F.Mask" "F.Paste")
			(net "GND")
		)
		(pad "33" smd rect
			(at -2.050034 -36.124896 90)
			(size 0.519938 1.4986)
			(layers "F.Cu" "F.Mask" "F.Paste")
			(net "M_G_CPU1_SA_DQS_DP<2>")
		)
		(pad "34" smd rect
			(at -2.050034 -35.275012 90)
			(size 0.519938 1.4986)
			(layers "F.Cu" "F.Mask" "F.Paste")
			(net "M_G_CPU1_SA_DQS_DN<2>")
		)
		(pad "35" smd rect
			(at -2.050034 -34.425128 90)
			(size 0.519938 1.4986)
			(layers "F.Cu" "F.Mask" "F.Paste")
			(net "GND")
		)
		(pad "36" smd rect
			(at -2.050034 -33.57499 90)
			(size 0.519938 1.4986)
			(layers "F.Cu" "F.Mask" "F.Paste")
			(net "M_G_CPU1_SA_DQ<20>")
		)
		(pad "37" smd rect
			(at -2.050034 -32.725106 90)
			(size 0.519938 1.4986)
			(layers "F.Cu" "F.Mask" "F.Paste")
			(net "GND")
		)
		(pad "38" smd rect
			(at -2.050034 -31.874968 90)
			(size 0.519938 1.4986)
			(layers "F.Cu" "F.Mask" "F.Paste")
			(net "M_G_CPU1_SA_DQ<21>")
		)
		(pad "39" smd rect
			(at -2.050034 -31.025084 90)
			(size 0.519938 1.4986)
			(layers "F.Cu" "F.Mask" "F.Paste")
			(net "GND")
		)
		(pad "40" smd rect
			(at -2.050034 -30.174946 90)
			(size 0.519938 1.4986)
			(layers "F.Cu" "F.Mask" "F.Paste")
			(net "M_G_CPU1_SA_DQ<24>")
		)
		(pad "41" smd rect
			(at -2.050034 -29.325062 90)
			(size 0.519938 1.4986)
			(layers "F.Cu" "F.Mask" "F.Paste")
			(net "GND")
		)
		(pad "42" smd rect
			(at -2.050034 -28.474924 90)
			(size 0.519938 1.4986)
			(layers "F.Cu" "F.Mask" "F.Paste")
			(net "M_G_CPU1_SA_DQ<25>")
		)
		(pad "43" smd rect
			(at -2.050034 -27.62504 90)
			(size 0.519938 1.4986)
			(layers "F.Cu" "F.Mask" "F.Paste")
			(net "GND")
		)
		(pad "44" smd rect
			(at -2.050034 -26.774902 90)
			(size 0.519938 1.4986)
			(layers "F.Cu" "F.Mask" "F.Paste")
			(net "M_G_CPU1_SA_DQS_DP<3>")
		)
		(pad "45" smd rect
			(at -2.050034 -25.925018 90)
			(size 0.519938 1.4986)
			(layers "F.Cu" "F.Mask" "F.Paste")
			(net "M_G_CPU1_SA_DQS_DN<3>")
		)
		(pad "46" smd rect
			(at -2.050034 -25.07488 90)
			(size 0.519938 1.4986)
			(layers "F.Cu" "F.Mask" "F.Paste")
			(net "GND")
		)
	)
)
